# S9S_MB_2U (Grand Teton) — schematic netlist excerpt (pin names and nets, part order shuffled) for the footprints in the layout excerpt that follows; sources: Cadence DE-HDL packaged netlist, KiCad conversion of 03242023_DA0F0TMBIJ0_F0T_Motherboard_J_brd_V01_OCP.brd

C1310  Q_CAP  10UF 6.3V 20% X6S  pkg C0603  page 210 : A = P3V3_AUX_CLK_GEN_VDDMXCK_CK440 ; B = GND

X32  TP_TDR_4P_FTS  TP_TDR_4P_DIP EMPTY  pkg TH  page 309
  S1  = TDR_DIFF_100_IN6_DN
  P1  = T1_GND
  P2  = T1_GND
  S2  = TDR_DIFF_100_IN6_DP

(kicad_pcb
	(version 20260206)
	(generator "pcbnew")
	(generator_version "10.0")
	(general
		(thickness 1.6)
		(legacy_teardrops no)
	)
	(paper "A4")
	(title_block
		(title "03242023_DA0F0TMBIJ0_F0T_Motherboard_J_brd_V01_OCP.brd")
		(comment 1 "Grand Teton / footprints 5467-5468 of 6105")
	)
	(layers
		(0 "F.Cu" signal "TOP")
		(4 "In1.Cu" signal "GND")
		(6 "In2.Cu" signal "IN1")
		(8 "In3.Cu" signal "GND1")
		(10 "In4.Cu" signal "IN2")
		(12 "In5.Cu" signal "GND2")
		(14 "In6.Cu" signal "IN3")
		(16 "In7.Cu" signal "GND3")
		(18 "In8.Cu" signal "VCC")
		(20 "In9.Cu" signal "VCC1")
		(22 "In10.Cu" signal "GND4")
		(24 "In11.Cu" signal "IN4")
		(26 "In12.Cu" signal "GND5")
		(28 "In13.Cu" signal "IN5")
		(30 "In14.Cu" signal "GND6")
		(32 "In15.Cu" signal "IN6")
		(34 "In16.Cu" signal "GND7")
		(2 "B.Cu" signal "BOTTOM")
		(9 "F.Adhes" user "F.Adhesive")
		(11 "B.Adhes" user "B.Adhesive")
		(13 "F.Paste" user "Package Geometry/Pastemask Top")
		(15 "B.Paste" user "Package Geometry/Pastemask Bottom")
		(5 "F.SilkS" user "Ref Des/Silkscreen Top")
		(7 "B.SilkS" user "Ref Des/Silkscreen Bottom")
		(1 "F.Mask" user "Board Geometry/Soldermask Top")
		(3 "B.Mask" user "Board Geometry/Soldermask Bottom")
		(17 "Dwgs.User" user "User.Drawings")
		(19 "Cmts.User" user "User.Comments")
		(21 "Eco1.User" user "User.Eco1")
		(23 "Eco2.User" user "User.Eco2")
		(25 "Edge.Cuts" user "Board Geometry/Outline")
		(27 "Margin" user)
		(31 "F.CrtYd" user "Package Geometry/Place Bound Top")
		(29 "B.CrtYd" user "Package Geometry/Place Bound Bottom")
		(35 "F.Fab" user "Ref Des/Assembly Top")
		(33 "B.Fab" user "Ref Des/Assembly Bottom")
	)
	(footprint ""
		(layer "B.Cu")
		(at 495.90833 -148.094192 -90)
		(property "Reference" "X32"
			(at 3.666236 3.151378 270)
			(unlocked yes)
			(layer "B.SilkS")
			(effects
				(font
					(size 0.7874 0.5842)
					(thickness 0.1524)
				)
				(justify left mirror)
			)
		)
		(property "Value" ""
			(at 0 0 90)
			(layer "B.Fab")
			(effects
				(font
					(size 1.27 1.27)
				)
				(justify mirror)
			)
		)
		(property "Device Type" "TP_TDR_4P_FTS_TH-TP_TDR_4P_DIPA"
			(at -1.30175 1.27 180)
			(unlocked yes)
			(layer "B.Fab")
			(hide yes)
			(effects
				(font
					(size 0.635 0.4064)
					(thickness 0.1524)
				)
				(justify mirror)
			)
		)
		(property "User Part Number" "N_A"
			(at -1.30175 1.27 180)
			(unlocked yes)
			(layer "Cmts.User")
			(hide yes)
			(effects
				(font
					(size 0.635 0.4064)
					(thickness 0.1524)
				)
				(justify mirror)
			)
		)
		(duplicate_pad_numbers_are_jumpers no)
		(fp_line
			(start -2.54 3.81)
			(end -2.54 3.6703)
			(stroke
				(width 0.1524)
				(type default)
			)
			(layer "B.SilkS")
		)
		(fp_line
			(start 0 3.81)
			(end -2.54 3.81)
			(stroke
				(width 0.1524)
				(type default)
			)
			(layer "B.SilkS")
		)
		(fp_line
			(start 0 3.175)
			(end 0 3.81)
			(stroke
				(width 0.1524)
				(type default)
			)
			(layer "B.SilkS")
		)
		(fp_line
			(start -2.54 1.4097)
			(end -2.54 1.1303)
			(stroke
				(width 0.1524)
				(type default)
			)
			(layer "B.SilkS")
		)
		(fp_line
			(start 0 0.635)
			(end 0 1.905)
			(stroke
				(width 0.1524)
				(type default)
			)
			(layer "B.SilkS")
		)
		(fp_line
			(start -2.54 -1.1303)
			(end -2.54 -1.27)
			(stroke
				(width 0.1524)
				(type default)
			)
			(layer "B.SilkS")
		)
		(fp_line
			(start -2.54 -1.27)
			(end 0 -1.27)
			(stroke
				(width 0.1524)
				(type default)
			)
			(layer "B.SilkS")
		)
		(fp_line
			(start 0 -1.27)
			(end 0 -0.635)
			(stroke
				(width 0.1524)
				(type default)
			)
			(layer "B.SilkS")
		)
		(fp_poly
			(pts
				(xy 2.981706 -0.88646) (xy 2.981706 0.63754) (xy 1.457706 -0.12446)
			)
			(stroke
				(width 0)
				(type default)
			)
			(fill yes)
			(layer "B.SilkS")
		)
		(fp_line
			(start -2.54 3.81)
			(end -2.54 -1.27)
			(stroke
				(width 0.1)
				(type default)
			)
			(layer "B.Fab")
		)
		(fp_line
			(start 0 3.81)
			(end -2.54 3.81)
			(stroke
				(width 0.1)
				(type default)
			)
			(layer "B.Fab")
		)
		(fp_line
			(start -2.54 -1.27)
			(end 0 -1.27)
			(stroke
				(width 0.1)
				(type default)
			)
			(layer "B.Fab")
		)
		(fp_line
			(start 0 -1.27)
			(end 0 3.81)
			(stroke
				(width 0.1)
				(type default)
			)
			(layer "B.Fab")
		)
		(fp_poly
			(pts
				(xy 0.761746 0) (xy 2.285746 -0.762) (xy 2.285746 0.762)
			)
			(stroke
				(width 0)
				(type default)
			)
			(fill yes)
			(layer "B.Fab")
		)
		(pad "1" thru_hole circle
			(at 0 0 90)
			(size 1.0033 1.0033)
			(drill 0.249936)
			(layers "*.Cu" "*.Mask")
			(remove_unused_layers no)
			(net "TDR_DIFF_100_IN6_DN")
			(clearance 0.10795)
			(padstack
				(mode front_inner_back)
				(layer "Inner"
					(shape circle)
					(size 0.8001 0.8001)
					(clearance 0.1524)
				)
				(layer "B.Cu"
					(shape circle)
					(size 1.0033 1.0033)
					(thermal_gap 0.10795)
					(clearance 0.10795)
				)
			)
		)
		(pad "2" thru_hole circle
			(at -2.54 0 90)
			(size 1.9939 1.9939)
			(drill 0.249936)
			(layers "*.Cu" "*.Mask")
			(remove_unused_layers no)
			(net "T1_GND")
			(clearance 0.10795)
			(padstack
				(mode front_inner_back)
				(layer "Inner"
					(shape circle)
					(size 0.8001 0.8001)
					(clearance 0.1524)
				)
				(layer "B.Cu"
					(shape circle)
					(size 1.9939 1.9939)
					(thermal_gap 0.10795)
					(clearance 0.10795)
				)
			)
		)
		(pad "3" thru_hole circle
			(at -2.54 2.54 90)
			(size 1.9939 1.9939)
			(drill 0.249936)
			(layers "*.Cu" "*.Mask")
			(remove_unused_layers no)
			(net "T1_GND")
			(clearance 0.10795)
			(padstack
				(mode front_inner_back)
				(layer "Inner"
					(shape circle)
					(size 0.8001 0.8001)
					(clearance 0.1524)
				)
				(layer "B.Cu"
					(shape circle)
					(size 1.9939 1.9939)
					(thermal_gap 0.10795)
					(clearance 0.10795)
				)
			)
		)
		(pad "4" thru_hole circle
			(at 0 2.54 90)
			(size 1.0033 1.0033)
			(drill 0.249936)
			(layers "*.Cu" "*.Mask")
			(remove_unused_layers no)
			(net "TDR_DIFF_100_IN6_DP")
			(clearance 0.10795)
			(padstack
				(mode front_inner_back)
				(layer "Inner"
					(shape circle)
					(size 0.8001 0.8001)
					(clearance 0.1524)
				)
				(layer "B.Cu"
					(shape circle)
					(size 1.0033 1.0033)
					(thermal_gap 0.10795)
					(clearance 0.10795)
				)
			)
		)
	)
	(footprint ""
		(layer "B.Cu")
		(at 261.655814 -100.91547 180)
		(property "Reference" "C1310"
			(at 0 0 0)
			(layer "B.SilkS")
			(hide yes)
			(effects
				(font
					(size 1.27 1.27)
				)
				(justify mirror)
			)
		)
		(property "Value" ""
			(at 0 0 0)
			(layer "B.Fab")
			(effects
				(font
					(size 1.27 1.27)
				)
				(justify mirror)
			)
		)
		(duplicate_pad_numbers_are_jumpers no)
		(fp_line
			(start 1.2954 0.5842)
			(end 1.2954 -0.5842)
			(stroke
				(width 0.1524)
				(type default)
			)
			(layer "B.SilkS")
		)
		(fp_line
			(start 1.2954 -0.5842)
			(end -1.2954 -0.5842)
			(stroke
				(width 0.1524)
				(type default)
			)
			(layer "B.SilkS")
		)
		(fp_line
			(start 0 -0.5842)
			(end 0 0.5842)
			(stroke
				(width 0.1524)
				(type default)
			)
			(layer "B.SilkS")
		)
		(fp_line
			(start -1.2954 0.5842)
			(end 1.2954 0.5842)
			(stroke
				(width 0.1524)
				(type default)
			)
			(layer "B.SilkS")
		)
		(fp_line
			(start -1.2954 -0.5842)
			(end -1.2954 0.5842)
			(stroke
				(width 0.1524)
				(type default)
			)
			(layer "B.SilkS")
		)
		(fp_line
			(start 1.1938 0.4064)
			(end 1.1938 -0.4064)
			(stroke
				(width 0.1)
				(type default)
			)
			(layer "B.Fab")
		)
		(fp_line
			(start 1.1938 -0.4064)
			(end 0.8636 -0.4064)
			(stroke
				(width 0.1)
				(type default)
			)
			(layer "B.Fab")
		)
		(fp_line
			(start 0.8636 0.4572)
			(end 0.8636 0.4064)
			(stroke
				(width 0.1)
				(type default)
			)
			(layer "B.Fab")
		)
		(fp_line
			(start 0.8636 0.4064)
			(end 1.1938 0.4064)
			(stroke
				(width 0.1)
				(type default)
			)
			(layer "B.Fab")
		)
		(fp_line
			(start 0.8636 -0.4064)
			(end 0.8636 -0.4572)
			(stroke
				(width 0.1)
				(type default)
			)
			(layer "B.Fab")
		)
		(fp_line
			(start 0.8636 -0.4572)
			(end -0.8636 -0.4572)
			(stroke
				(width 0.1)
				(type default)
			)
			(layer "B.Fab")
		)
		(fp_line
			(start -0.8636 0.4572)
			(end 0.8636 0.4572)
			(stroke
				(width 0.1)
				(type default)
			)
			(layer "B.Fab")
		)
		(fp_line
			(start -0.8636 0.4064)
			(end -0.8636 0.4572)
			(stroke
				(width 0.1)
				(type default)
			)
			(layer "B.Fab")
		)
		(fp_line
			(start -0.8636 -0.4064)
			(end -1.1938 -0.4064)
			(stroke
				(width 0.1)
				(type default)
			)
			(layer "B.Fab")
		)
		(fp_line
			(start -0.8636 -0.4572)
			(end -0.8636 -0.4064)
			(stroke
				(width 0.1)
				(type default)
			)
			(layer "B.Fab")
		)
		(fp_line
			(start -1.1938 0.4064)
			(end -0.8636 0.4064)
			(stroke
				(width 0.1)
				(type default)
			)
			(layer "B.Fab")
		)
		(fp_line
			(start -1.1938 -0.4064)
			(end -1.1938 0.4064)
			(stroke
				(width 0.1)
				(type default)
			)
			(layer "B.Fab")
		)
		(pad "1" smd rect
			(at 0.7366 0 90)
			(size 0.7112 0.8128)
			(layers "B.Cu" "B.Mask" "B.Paste")
			(net "P3V3_AUX_CLK_GEN_VDDMXCK_CK440")
		)
		(pad "2" smd rect
			(at -0.7366 0 90)
			(size 0.7112 0.8128)
			(layers "B.Cu" "B.Mask" "B.Paste")
			(net "GND")
		)
	)
)
